(kicad_pcb
	(version 20260206)
	(generator "pcbnew")
	(generator_version "10.0")
	(general
		(thickness 1.6)
		(legacy_teardrops no)
	)
	(paper "A4")
	(title_block
		(title "Bryce Canyon_IOM_IOC_16318-2_OCP.brd")
		(comment 1 "Bryce Canyon / footprints 659-666 of 1605")
	)
	(layers
		(0 "F.Cu" signal "TOP")
		(4 "In1.Cu" signal "L2GND")
		(6 "In2.Cu" signal "L3")
		(8 "In3.Cu" signal "L4VCC")
		(10 "In4.Cu" signal "L5VCC")
		(12 "In5.Cu" signal "L6")
		(14 "In6.Cu" signal "L7GND")
		(2 "B.Cu" signal "BOTTOM")
		(9 "F.Adhes" user "F.Adhesive")
		(11 "B.Adhes" user "B.Adhesive")
		(13 "F.Paste" user "Package Geometry/Pastemask Top")
		(15 "B.Paste" user "Package Geometry/Pastemask Bottom")
		(5 "F.SilkS" user "Ref Des/Silkscreen Top")
		(7 "B.SilkS" user "Ref Des/Silkscreen Bottom")
		(1 "F.Mask" user "Board Geometry/Soldermask Top")
		(3 "B.Mask" user "Board Geometry/Soldermask Bottom")
		(17 "Dwgs.User" user "User.Drawings")
		(19 "Cmts.User" user "User.Comments")
		(21 "Eco1.User" user "User.Eco1")
		(23 "Eco2.User" user "User.Eco2")
		(25 "Edge.Cuts" user "Board Geometry/Outline")
		(27 "Margin" user)
		(31 "F.CrtYd" user "Package Geometry/Place Bound Top")
		(29 "B.CrtYd" user "Package Geometry/Place Bound Bottom")
		(35 "F.Fab" user "Ref Des/Assembly Top")
		(33 "B.Fab" user "Ref Des/Assembly Bottom")
	)
	(footprint ""
		(layer "F.Cu")
		(at 218.694 -102.8954 180)
		(property "Reference" "R605"
			(at 0 0 180)
			(layer "F.SilkS")
			(hide yes)
			(effects
				(font
					(size 1.27 1.27)
				)
			)
		)
		(property "Value" "4K7R2F-GP"
			(at 0.064008 -3.993896 180)
			(unlocked yes)
			(layer "F.Fab")
			(hide yes)
			(effects
				(font
					(size 1.016 1.016)
					(thickness 0.1524)
				)
			)
		)
		(property "Device Type" "R402H16"
			(at 0.064008 -5.517896 180)
			(unlocked yes)
			(layer "F.Fab")
			(hide yes)
			(effects
				(font
					(size 1.016 1.016)
					(thickness 0.1524)
				)
			)
		)
		(duplicate_pad_numbers_are_jumpers no)
		(fp_line
			(start 0.508 -0.9398)
			(end -0.508 -0.9398)
			(stroke
				(width 0.1524)
				(type default)
			)
			(layer "F.SilkS")
		)
		(fp_line
			(start -0.508 -0.9398)
			(end -0.508 0.9398)
			(stroke
				(width 0.1524)
				(type default)
			)
			(layer "F.SilkS")
		)
		(fp_rect
			(start -0.508 0.9398)
			(end 0.508 -0.9398)
			(stroke
				(width 0)
				(type default)
			)
			(fill no)
			(layer "F.CrtYd")
		)
		(fp_rect
			(start -0.508 0.9398)
			(end 0.508 -0.9398)
			(stroke
				(width 0)
				(type default)
			)
			(fill no)
			(layer "F.Fab")
		)
		(pad "1" smd custom
			(at 0 -0.4445 180)
			(size 0.1397 0.1397)
			(layers "F.Cu" "F.Mask" "F.Paste")
			(net "IOC_EEPROM_A2")
			(options
				(clearance outline)
				(anchor circle)
			)
			(primitives
				(gr_poly
					(pts
						(arc
							(start -0.1778 -0.2794)
							(mid -0.249642 -0.249642)
							(end -0.2794 -0.1778)
						)
						(arc
							(start -0.2794 0.1778)
							(mid -0.249642 0.249642)
							(end -0.1778 0.2794)
						)
						(arc
							(start 0.1778 0.2794)
							(mid 0.249642 0.249642)
							(end 0.2794 0.1778)
						)
						(arc
							(start 0.2794 -0.1778)
							(mid 0.249642 -0.249642)
							(end 0.1778 -0.2794)
						)
					)
					(width 0)
					(fill yes)
				)
			)
		)
		(pad "2" smd custom
			(at 0 0.4445 180)
			(size 0.1397 0.1397)
			(layers "F.Cu" "F.Mask" "F.Paste")
			(net "GND")
			(options
				(clearance outline)
				(anchor circle)
			)
			(primitives
				(gr_poly
					(pts
						(arc
							(start -0.1778 -0.2794)
							(mid -0.249642 -0.249642)
							(end -0.2794 -0.1778)
						)
						(arc
							(start -0.2794 0.1778)
							(mid -0.249642 0.249642)
							(end -0.1778 0.2794)
						)
						(arc
							(start 0.1778 0.2794)
							(mid 0.249642 0.249642)
							(end 0.2794 0.1778)
						)
						(arc
							(start 0.2794 -0.1778)
							(mid 0.249642 -0.249642)
							(end 0.1778 -0.2794)
						)
					)
					(width 0)
					(fill yes)
				)
			)
		)
	)
	(footprint ""
		(layer "F.Cu")
		(at 74.4601 -136.398 180)
		(property "Reference" "R738"
			(at 0 0 180)
			(layer "F.SilkS")
			(hide yes)
			(effects
				(font
					(size 1.27 1.27)
				)
			)
		)
		(property "Value" "4K7R2F-GP"
			(at 0.064008 -3.993896 180)
			(unlocked yes)
			(layer "F.Fab")
			(hide yes)
			(effects
				(font
					(size 1.016 1.016)
					(thickness 0.1524)
				)
			)
		)
		(property "Device Type" "R402H16"
			(at 0.064008 -5.517896 180)
			(unlocked yes)
			(layer "F.Fab")
			(hide yes)
			(effects
				(font
					(size 1.016 1.016)
					(thickness 0.1524)
				)
			)
		)
		(duplicate_pad_numbers_are_jumpers no)
		(fp_line
			(start 0.508 -0.9398)
			(end -0.508 -0.9398)
			(stroke
				(width 0.1524)
				(type default)
			)
			(layer "F.SilkS")
		)
		(fp_line
			(start -0.508 -0.9398)
			(end -0.508 0.9398)
			(stroke
				(width 0.1524)
				(type default)
			)
			(layer "F.SilkS")
		)
		(fp_rect
			(start -0.508 0.9398)
			(end 0.508 -0.9398)
			(stroke
				(width 0)
				(type default)
			)
			(fill no)
			(layer "F.CrtYd")
		)
		(fp_rect
			(start -0.508 0.9398)
			(end 0.508 -0.9398)
			(stroke
				(width 0)
				(type default)
			)
			(fill no)
			(layer "F.Fab")
		)
		(pad "1" smd custom
			(at 0 -0.4445 180)
			(size 0.1397 0.1397)
			(layers "F.Cu" "F.Mask" "F.Paste")
			(net "P3V3_STBY")
			(options
				(clearance outline)
				(anchor circle)
			)
			(primitives
				(gr_poly
					(pts
						(arc
							(start -0.1778 -0.2794)
							(mid -0.249642 -0.249642)
							(end -0.2794 -0.1778)
						)
						(arc
							(start -0.2794 0.1778)
							(mid -0.249642 0.249642)
							(end -0.1778 0.2794)
						)
						(arc
							(start 0.1778 0.2794)
							(mid 0.249642 0.249642)
							(end 0.2794 0.1778)
						)
						(arc
							(start 0.2794 -0.1778)
							(mid 0.249642 -0.249642)
							(end 0.1778 -0.2794)
						)
					)
					(width 0)
					(fill yes)
				)
			)
		)
		(pad "2" smd custom
			(at 0 0.4445 180)
			(size 0.1397 0.1397)
			(layers "F.Cu" "F.Mask" "F.Paste")
			(net "DEBUG_HDR_UART_SEL")
			(options
				(clearance outline)
				(anchor circle)
			)
			(primitives
				(gr_poly
					(pts
						(arc
							(start -0.1778 -0.2794)
							(mid -0.249642 -0.249642)
							(end -0.2794 -0.1778)
						)
						(arc
							(start -0.2794 0.1778)
							(mid -0.249642 0.249642)
							(end -0.1778 0.2794)
						)
						(arc
							(start 0.1778 0.2794)
							(mid 0.249642 0.249642)
							(end 0.2794 0.1778)
						)
						(arc
							(start 0.2794 -0.1778)
							(mid 0.249642 -0.249642)
							(end 0.1778 -0.2794)
						)
					)
					(width 0)
					(fill yes)
				)
			)
		)
	)
	(footprint ""
		(layer "F.Cu")
		(at 28.2448 -180.7464)
		(property "Reference" "R495"
			(at 0 0 0)
			(layer "F.SilkS")
			(hide yes)
			(effects
				(font
					(size 1.27 1.27)
				)
			)
		)
		(property "Value" "866KR2F-GP"
			(at 0.064008 -3.993896 0)
			(unlocked yes)
			(layer "F.Fab")
			(hide yes)
			(effects
				(font
					(size 1.016 1.016)
					(thickness 0.1524)
				)
			)
		)
		(property "Device Type" "R402H16"
			(at 0.064008 -5.517896 0)
			(unlocked yes)
			(layer "F.Fab")
			(hide yes)
			(effects
				(font
					(size 1.016 1.016)
					(thickness 0.1524)
				)
			)
		)
		(duplicate_pad_numbers_are_jumpers no)
		(fp_line
			(start -0.508 -0.9398)
			(end -0.508 0.9398)
			(stroke
				(width 0.1524)
				(type default)
			)
			(layer "F.SilkS")
		)
		(fp_line
			(start 0.508 -0.9398)
			(end -0.508 -0.9398)
			(stroke
				(width 0.1524)
				(type default)
			)
			(layer "F.SilkS")
		)
		(fp_rect
			(start -0.508 0.9398)
			(end 0.508 -0.9398)
			(stroke
				(width 0)
				(type default)
			)
			(fill no)
			(layer "F.CrtYd")
		)
		(fp_rect
			(start -0.508 0.9398)
			(end 0.508 -0.9398)
			(stroke
				(width 0)
				(type default)
			)
			(fill no)
			(layer "F.Fab")
		)
		(pad "1" smd custom
			(at 0 -0.4445)
			(size 0.1397 0.1397)
			(layers "F.Cu" "F.Mask" "F.Paste")
			(net "P3V3_STBY_VREG")
			(options
				(clearance outline)
				(anchor circle)
			)
			(primitives
				(gr_poly
					(pts
						(arc
							(start -0.1778 -0.2794)
							(mid -0.249642 -0.249642)
							(end -0.2794 -0.1778)
						)
						(arc
							(start -0.2794 0.1778)
							(mid -0.249642 0.249642)
							(end -0.1778 0.2794)
						)
						(arc
							(start 0.1778 0.2794)
							(mid 0.249642 0.249642)
							(end 0.2794 0.1778)
						)
						(arc
							(start 0.2794 -0.1778)
							(mid 0.249642 -0.249642)
							(end 0.1778 -0.2794)
						)
					)
					(width 0)
					(fill yes)
				)
			)
		)
		(pad "2" smd custom
			(at 0 0.4445)
			(size 0.1397 0.1397)
			(layers "F.Cu" "F.Mask" "F.Paste")
			(net "P3V3_STBY_RF")
			(options
				(clearance outline)
				(anchor circle)
			)
			(primitives
				(gr_poly
					(pts
						(arc
							(start -0.1778 -0.2794)
							(mid -0.249642 -0.249642)
							(end -0.2794 -0.1778)
						)
						(arc
							(start -0.2794 0.1778)
							(mid -0.249642 0.249642)
							(end -0.1778 0.2794)
						)
						(arc
							(start 0.1778 0.2794)
							(mid 0.249642 0.249642)
							(end 0.2794 0.1778)
						)
						(arc
							(start 0.2794 -0.1778)
							(mid 0.249642 -0.249642)
							(end 0.1778 -0.2794)
						)
					)
					(width 0)
					(fill yes)
				)
			)
		)
	)
	(footprint ""
		(layer "F.Cu")
		(at 122.9614 -17.265142 90)
		(property "Reference" "R434"
			(at 0 0 90)
			(layer "F.SilkS")
			(hide yes)
			(effects
				(font
					(size 1.27 1.27)
				)
			)
		)
		(property "Value" "100R2D-GP"
			(at 0.064008 -3.993896 90)
			(unlocked yes)
			(layer "F.Fab")
			(hide yes)
			(effects
				(font
					(size 1.016 1.016)
					(thickness 0.1524)
				)
			)
		)
		(property "Device Type" "R402H14"
			(at 0.064008 -5.517896 90)
			(unlocked yes)
			(layer "F.Fab")
			(hide yes)
			(effects
				(font
					(size 1.016 1.016)
					(thickness 0.1524)
				)
			)
		)
		(duplicate_pad_numbers_are_jumpers no)
		(fp_line
			(start 0.508 -0.9398)
			(end -0.508 -0.9398)
			(stroke
				(width 0.1524)
				(type default)
			)
			(layer "F.SilkS")
		)
		(fp_line
			(start -0.508 -0.9398)
			(end -0.508 0.9398)
			(stroke
				(width 0.1524)
				(type default)
			)
			(layer "F.SilkS")
		)
		(fp_rect
			(start -0.508 0.9398)
			(end 0.508 -0.9398)
			(stroke
				(width 0)
				(type default)
			)
			(fill no)
			(layer "F.CrtYd")
		)
		(fp_rect
			(start -0.508 0.9398)
			(end 0.508 -0.9398)
			(stroke
				(width 0)
				(type default)
			)
			(fill no)
			(layer "F.Fab")
		)
		(pad "1" smd custom
			(at 0 -0.4445 90)
			(size 0.1397 0.1397)
			(layers "F.Cu" "F.Mask" "F.Paste")
			(net "GND")
			(options
				(clearance outline)
				(anchor circle)
			)
			(primitives
				(gr_poly
					(pts
						(arc
							(start -0.1778 -0.2794)
							(mid -0.249642 -0.249642)
							(end -0.2794 -0.1778)
						)
						(arc
							(start -0.2794 0.1778)
							(mid -0.249642 0.249642)
							(end -0.1778 0.2794)
						)
						(arc
							(start 0.1778 0.2794)
							(mid 0.249642 0.249642)
							(end 0.2794 0.1778)
						)
						(arc
							(start 0.2794 -0.1778)
							(mid 0.249642 -0.249642)
							(end 0.1778 -0.2794)
						)
					)
					(width 0)
					(fill yes)
				)
			)
		)
		(pad "2" smd custom
			(at 0 0.4445 90)
			(size 0.1397 0.1397)
			(layers "F.Cu" "F.Mask" "F.Paste")
			(net "MB0_TEMP_E")
			(options
				(clearance outline)
				(anchor circle)
			)
			(primitives
				(gr_poly
					(pts
						(arc
							(start -0.1778 -0.2794)
							(mid -0.249642 -0.249642)
							(end -0.2794 -0.1778)
						)
						(arc
							(start -0.2794 0.1778)
							(mid -0.249642 0.249642)
							(end -0.1778 0.2794)
						)
						(arc
							(start 0.1778 0.2794)
							(mid 0.249642 0.249642)
							(end 0.2794 0.1778)
						)
						(arc
							(start 0.2794 -0.1778)
							(mid 0.249642 -0.249642)
							(end 0.1778 -0.2794)
						)
					)
					(width 0)
					(fill yes)
				)
			)
		)
	)
	(footprint ""
		(layer "F.Cu")
		(at 53.4416 -125.8062 90)
		(property "Reference" "R269"
			(at 0 0 90)
			(layer "F.SilkS")
			(hide yes)
			(effects
				(font
					(size 1.27 1.27)
				)
			)
		)
		(property "Value" "2K2R2J-2-GP"
			(at 0.064008 -3.993896 90)
			(unlocked yes)
			(layer "F.Fab")
			(hide yes)
			(effects
				(font
					(size 1.016 1.016)
					(thickness 0.1524)
				)
			)
		)
		(property "Device Type" "R402H16"
			(at 0.064008 -5.517896 90)
			(unlocked yes)
			(layer "F.Fab")
			(hide yes)
			(effects
				(font
					(size 1.016 1.016)
					(thickness 0.1524)
				)
			)
		)
		(duplicate_pad_numbers_are_jumpers no)
		(fp_line
			(start 0.508 -0.9398)
			(end -0.508 -0.9398)
			(stroke
				(width 0.1524)
				(type default)
			)
			(layer "F.SilkS")
		)
		(fp_line
			(start -0.508 -0.9398)
			(end -0.508 0.9398)
			(stroke
				(width 0.1524)
				(type default)
			)
			(layer "F.SilkS")
		)
		(fp_rect
			(start -0.508 0.9398)
			(end 0.508 -0.9398)
			(stroke
				(width 0)
				(type default)
			)
			(fill no)
			(layer "F.CrtYd")
		)
		(fp_rect
			(start -0.508 0.9398)
			(end 0.508 -0.9398)
			(stroke
				(width 0)
				(type default)
			)
			(fill no)
			(layer "F.Fab")
		)
		(pad "1" smd custom
			(at 0 -0.4445 90)
			(size 0.1397 0.1397)
			(layers "F.Cu" "F.Mask" "F.Paste")
			(net "P3V3_STBY")
			(options
				(clearance outline)
				(anchor circle)
			)
			(primitives
				(gr_poly
					(pts
						(arc
							(start -0.1778 -0.2794)
							(mid -0.249642 -0.249642)
							(end -0.2794 -0.1778)
						)
						(arc
							(start -0.2794 0.1778)
							(mid -0.249642 0.249642)
							(end -0.1778 0.2794)
						)
						(arc
							(start 0.1778 0.2794)
							(mid 0.249642 0.249642)
							(end 0.2794 0.1778)
						)
						(arc
							(start 0.2794 -0.1778)
							(mid 0.249642 -0.249642)
							(end 0.1778 -0.2794)
						)
					)
					(width 0)
					(fill yes)
				)
			)
		)
		(pad "2" smd custom
			(at 0 0.4445 90)
			(size 0.1397 0.1397)
			(layers "F.Cu" "F.Mask" "F.Paste")
			(net "FLA1_WP_N")
			(options
				(clearance outline)
				(anchor circle)
			)
			(primitives
				(gr_poly
					(pts
						(arc
							(start -0.1778 -0.2794)
							(mid -0.249642 -0.249642)
							(end -0.2794 -0.1778)
						)
						(arc
							(start -0.2794 0.1778)
							(mid -0.249642 0.249642)
							(end -0.1778 0.2794)
						)
						(arc
							(start 0.1778 0.2794)
							(mid 0.249642 0.249642)
							(end 0.2794 0.1778)
						)
						(arc
							(start 0.2794 -0.1778)
							(mid 0.249642 -0.249642)
							(end 0.1778 -0.2794)
						)
					)
					(width 0)
					(fill yes)
				)
			)
		)
	)
	(footprint ""
		(layer "F.Cu")
		(at 184.1754 -110.109 90)
		(property "Reference" "C269"
			(at 0 0 90)
			(layer "F.SilkS")
			(hide yes)
			(effects
				(font
					(size 1.27 1.27)
				)
			)
		)
		(property "Value" "SC10U16V5KX-7-GP-U"
			(at -0.0762 -6.1214 90)
			(unlocked yes)
			(layer "F.Fab")
			(hide yes)
			(effects
				(font
					(size 1.016 1.016)
					(thickness 0.1524)
				)
			)
		)
		(property "Device Type" "C805H58"
			(at -0.0762 -8.1534 90)
			(unlocked yes)
			(layer "F.Fab")
			(hide yes)
			(effects
				(font
					(size 1.016 1.016)
					(thickness 0.1524)
				)
			)
		)
		(duplicate_pad_numbers_are_jumpers no)
		(fp_line
			(start 0.635 0)
			(end -0.635 0)
			(stroke
				(width 0.508)
				(type default)
			)
			(layer "F.SilkS")
		)
		(fp_rect
			(start -0.9652 1.778)
			(end 0.9652 -1.778)
			(stroke
				(width 0)
				(type default)
			)
			(fill no)
			(layer "F.CrtYd")
		)
		(fp_poly
			(pts
				(xy -0.9652 -1.778) (xy 0.9652 -1.778) (xy 0.9652 1.778) (xy -0.9652 1.778)
			)
			(stroke
				(width 0)
				(type default)
			)
			(fill no)
			(layer "F.Fab")
		)
		(pad "1" smd rect
			(at 0 -0.9652 90)
			(size 1.397 1.143)
			(layers "F.Cu" "F.Mask" "F.Paste")
			(net "VT235_VDDH")
		)
		(pad "2" smd rect
			(at 0 0.9652 90)
			(size 1.397 1.143)
			(layers "F.Cu" "F.Mask" "F.Paste")
			(net "GND")
		)
	)
	(footprint ""
		(layer "F.Cu")
		(at 67.2084 -144.0942 -90)
		(property "Reference" "R385"
			(at 0 0 270)
			(layer "F.SilkS")
			(hide yes)
			(effects
				(font
					(size 1.27 1.27)
				)
			)
		)
		(property "Value" "4K7R2F-GP"
			(at 0.064008 -3.993896 270)
			(unlocked yes)
			(layer "F.Fab")
			(hide yes)
			(effects
				(font
					(size 1.016 1.016)
					(thickness 0.1524)
				)
			)
		)
		(property "Device Type" "R402H16"
			(at 0.064008 -5.517896 270)
			(unlocked yes)
			(layer "F.Fab")
			(hide yes)
			(effects
				(font
					(size 1.016 1.016)
					(thickness 0.1524)
				)
			)
		)
		(duplicate_pad_numbers_are_jumpers no)
		(fp_line
			(start -0.508 -0.9398)
			(end -0.508 0.9398)
			(stroke
				(width 0.1524)
				(type default)
			)
			(layer "F.SilkS")
		)
		(fp_line
			(start 0.508 -0.9398)
			(end -0.508 -0.9398)
			(stroke
				(width 0.1524)
				(type default)
			)
			(layer "F.SilkS")
		)
		(fp_rect
			(start -0.508 0.9398)
			(end 0.508 -0.9398)
			(stroke
				(width 0)
				(type default)
			)
			(fill no)
			(layer "F.CrtYd")
		)
		(fp_rect
			(start -0.508 0.9398)
			(end 0.508 -0.9398)
			(stroke
				(width 0)
				(type default)
			)
			(fill no)
			(layer "F.Fab")
		)
		(pad "1" smd custom
			(at 0 -0.4445 270)
			(size 0.1397 0.1397)
			(layers "F.Cu" "F.Mask" "F.Paste")
			(net "GND")
			(options
				(clearance outline)
				(anchor circle)
			)
			(primitives
				(gr_poly
					(pts
						(arc
							(start -0.1778 -0.2794)
							(mid -0.249642 -0.249642)
							(end -0.2794 -0.1778)
						)
						(arc
							(start -0.2794 0.1778)
							(mid -0.249642 0.249642)
							(end -0.1778 0.2794)
						)
						(arc
							(start 0.1778 0.2794)
							(mid 0.249642 0.249642)
							(end 0.2794 0.1778)
						)
						(arc
							(start 0.2794 -0.1778)
							(mid 0.249642 -0.249642)
							(end 0.1778 -0.2794)
						)
					)
					(width 0)
					(fill yes)
				)
			)
		)
		(pad "2" smd custom
			(at 0 0.4445 270)
			(size 0.1397 0.1397)
			(layers "F.Cu" "F.Mask" "F.Paste")
			(net "NCSI_TXEN")
			(options
				(clearance outline)
				(anchor circle)
			)
			(primitives
				(gr_poly
					(pts
						(arc
							(start -0.1778 -0.2794)
							(mid -0.249642 -0.249642)
							(end -0.2794 -0.1778)
						)
						(arc
							(start -0.2794 0.1778)
							(mid -0.249642 0.249642)
							(end -0.1778 0.2794)
						)
						(arc
							(start 0.1778 0.2794)
							(mid 0.249642 0.249642)
							(end 0.2794 0.1778)
						)
						(arc
							(start 0.2794 -0.1778)
							(mid 0.249642 -0.249642)
							(end 0.1778 -0.2794)
						)
					)
					(width 0)
					(fill yes)
				)
			)
		)
	)
	(footprint ""
		(layer "F.Cu")
		(at 188.6458 -117.21592)
		(property "Reference" "R7909"
			(at 0 0 0)
			(layer "F.SilkS")
			(hide yes)
			(effects
				(font
					(size 1.27 1.27)
				)
			)
		)
		(property "Value" "2D2R5F-2-GP"
			(at 0 -8.9535 0)
			(unlocked yes)
			(layer "F.Fab")
			(hide yes)
			(effects
				(font
					(size 1.27 1.016)
					(thickness 0.1524)
				)
			)
		)
		(property "Device Type" "R805H24"
			(at 0 -10.6299 0)
			(unlocked yes)
			(layer "F.Fab")
			(hide yes)
			(effects
				(font
					(size 1.27 1.016)
					(thickness 0.1524)
				)
			)
		)
		(duplicate_pad_numbers_are_jumpers no)
		(fp_line
			(start -0.889 -1.7018)
			(end -0.889 0.2794)
			(stroke
				(width 0.1524)
				(type default)
			)
			(layer "F.SilkS")
		)
		(fp_line
			(start -0.889 0.0762)
			(end -0.889 1.7018)
			(stroke
				(width 0.1524)
				(type default)
			)
			(layer "F.SilkS")
		)
		(fp_line
			(start -0.889 1.7018)
			(end 0.889 1.7018)
			(stroke
				(width 0.1524)
				(type default)
			)
			(layer "F.SilkS")
		)
		(fp_line
			(start 0.889 -1.7018)
			(end -0.889 -1.7018)
			(stroke
				(width 0.1524)
				(type default)
			)
			(layer "F.SilkS")
		)
		(fp_line
			(start 0.889 -1.7018)
			(end 0.889 -0.381)
			(stroke
				(width 0.1524)
				(type default)
			)
			(layer "F.SilkS")
		)
		(fp_line
			(start 0.889 1.7018)
			(end 0.889 -0.508)
			(stroke
				(width 0.1524)
				(type default)
			)
			(layer "F.SilkS")
		)
		(fp_poly
			(pts
				(xy 0.9652 -1.778) (xy 0.9652 1.778) (xy -0.9652 1.778) (xy -0.9652 -1.778)
			)
			(stroke
				(width 0)
				(type default)
			)
			(fill no)
			(layer "F.CrtYd")
		)
		(fp_rect
			(start -0.9652 1.778)
			(end 0.9652 -1.778)
			(stroke
				(width 0)
				(type default)
			)
			(fill no)
			(layer "F.Fab")
		)
		(pad "1" smd rect
			(at 0 -0.9652)
			(size 1.397 1.143)
			(layers "F.Cu" "F.Mask" "F.Paste")
			(net "VT235_VX")
		)
		(pad "2" smd rect
			(at 0 0.9652)
			(size 1.397 1.143)
			(layers "F.Cu" "F.Mask" "F.Paste")
			(net "N62640349")
		)
	)
)
